(kicad_pcb
	(version 20260206)
	(generator "pcbnew")
	(generator_version "10.0")
	(general
		(thickness 1.6)
		(legacy_teardrops no)
	)
	(paper "A4")
	(title_block
		(title "03242023_DA0F0TMBIJ0_F0T_Motherboard_J_brd_V01_OCP.brd")
		(comment 1 "Grand Teton / footprints 428-433 of 6105")
	)
	(layers
		(0 "F.Cu" signal "TOP")
		(4 "In1.Cu" signal "GND")
		(6 "In2.Cu" signal "IN1")
		(8 "In3.Cu" signal "GND1")
		(10 "In4.Cu" signal "IN2")
		(12 "In5.Cu" signal "GND2")
		(14 "In6.Cu" signal "IN3")
		(16 "In7.Cu" signal "GND3")
		(18 "In8.Cu" signal "VCC")
		(20 "In9.Cu" signal "VCC1")
		(22 "In10.Cu" signal "GND4")
		(24 "In11.Cu" signal "IN4")
		(26 "In12.Cu" signal "GND5")
		(28 "In13.Cu" signal "IN5")
		(30 "In14.Cu" signal "GND6")
		(32 "In15.Cu" signal "IN6")
		(34 "In16.Cu" signal "GND7")
		(2 "B.Cu" signal "BOTTOM")
		(9 "F.Adhes" user "F.Adhesive")
		(11 "B.Adhes" user "B.Adhesive")
		(13 "F.Paste" user "Package Geometry/Pastemask Top")
		(15 "B.Paste" user "Package Geometry/Pastemask Bottom")
		(5 "F.SilkS" user "Ref Des/Silkscreen Top")
		(7 "B.SilkS" user "Ref Des/Silkscreen Bottom")
		(1 "F.Mask" user "Board Geometry/Soldermask Top")
		(3 "B.Mask" user "Board Geometry/Soldermask Bottom")
		(17 "Dwgs.User" user "User.Drawings")
		(19 "Cmts.User" user "User.Comments")
		(21 "Eco1.User" user "User.Eco1")
		(23 "Eco2.User" user "User.Eco2")
		(25 "Edge.Cuts" user "Board Geometry/Outline")
		(27 "Margin" user)
		(31 "F.CrtYd" user "Package Geometry/Place Bound Top")
		(29 "B.CrtYd" user "Package Geometry/Place Bound Bottom")
		(35 "F.Fab" user "Ref Des/Assembly Top")
		(33 "B.Fab" user "Ref Des/Assembly Bottom")
	)
	(footprint ""
		(layer "F.Cu")
		(at 304.1396 -421.49395 90)
		(property "Reference" "R4128"
			(at 0 0 90)
			(layer "F.SilkS")
			(hide yes)
			(effects
				(font
					(size 1.27 1.27)
				)
			)
		)
		(property "Value" ""
			(at 0 0 90)
			(layer "F.Fab")
			(effects
				(font
					(size 1.27 1.27)
				)
			)
		)
		(duplicate_pad_numbers_are_jumpers no)
		(fp_line
			(start 0.7874 -0.4064)
			(end 0.7874 0.4064)
			(stroke
				(width 0.1524)
				(type default)
			)
			(layer "F.SilkS")
		)
		(fp_line
			(start -0.7874 -0.4064)
			(end 0.7874 -0.4064)
			(stroke
				(width 0.1524)
				(type default)
			)
			(layer "F.SilkS")
		)
		(fp_line
			(start 0.7874 0.4064)
			(end -0.7874 0.4064)
			(stroke
				(width 0.1524)
				(type default)
			)
			(layer "F.SilkS")
		)
		(fp_line
			(start -0.7874 0.4064)
			(end -0.7874 -0.4064)
			(stroke
				(width 0.1524)
				(type default)
			)
			(layer "F.SilkS")
		)
		(fp_line
			(start -0.12065 -0.305054)
			(end -0.12065 -0.2794)
			(stroke
				(width 0.1)
				(type default)
			)
			(layer "F.Fab")
		)
		(fp_line
			(start -0.67945 -0.305054)
			(end -0.12065 -0.305054)
			(stroke
				(width 0.1)
				(type default)
			)
			(layer "F.Fab")
		)
		(fp_line
			(start 0.67945 -0.3048)
			(end 0.67945 0.3048)
			(stroke
				(width 0.1)
				(type default)
			)
			(layer "F.Fab")
		)
		(fp_line
			(start 0.12065 -0.3048)
			(end 0.67945 -0.3048)
			(stroke
				(width 0.1)
				(type default)
			)
			(layer "F.Fab")
		)
		(fp_line
			(start 0.12065 -0.2794)
			(end 0.12065 -0.3048)
			(stroke
				(width 0.1)
				(type default)
			)
			(layer "F.Fab")
		)
		(fp_line
			(start -0.12065 -0.2794)
			(end 0.12065 -0.2794)
			(stroke
				(width 0.1)
				(type default)
			)
			(layer "F.Fab")
		)
		(fp_line
			(start 0.120396 0.2794)
			(end -0.12065 0.2794)
			(stroke
				(width 0.1)
				(type default)
			)
			(layer "F.Fab")
		)
		(fp_line
			(start -0.12065 0.2794)
			(end -0.12065 0.3048)
			(stroke
				(width 0.1)
				(type default)
			)
			(layer "F.Fab")
		)
		(fp_line
			(start 0.67945 0.3048)
			(end 0.120396 0.3048)
			(stroke
				(width 0.1)
				(type default)
			)
			(layer "F.Fab")
		)
		(fp_line
			(start 0.120396 0.3048)
			(end 0.120396 0.2794)
			(stroke
				(width 0.1)
				(type default)
			)
			(layer "F.Fab")
		)
		(fp_line
			(start -0.12065 0.3048)
			(end -0.67945 0.3048)
			(stroke
				(width 0.1)
				(type default)
			)
			(layer "F.Fab")
		)
		(fp_line
			(start -0.67945 0.3048)
			(end -0.67945 -0.305054)
			(stroke
				(width 0.1)
				(type default)
			)
			(layer "F.Fab")
		)
		(pad "1" smd circle
			(at -0.40005 0 90)
			(size 0 0)
			(layers "F.Cu" "F.Mask" "F.Paste")
			(net "P3V3_AUX")
		)
		(pad "2" smd circle
			(at 0.40005 0 90)
			(size 0 0)
			(layers "F.Cu" "F.Mask" "F.Paste")
			(net "GPU_3V3IO_RSVD0_FFU_ISO")
		)
	)
	(footprint ""
		(layer "F.Cu")
		(at 418.6936 -51.87442 90)
		(property "Reference" "R4677"
			(at 0 0 90)
			(layer "F.SilkS")
			(hide yes)
			(effects
				(font
					(size 1.27 1.27)
				)
			)
		)
		(property "Value" ""
			(at 0 0 90)
			(layer "F.Fab")
			(effects
				(font
					(size 1.27 1.27)
				)
			)
		)
		(duplicate_pad_numbers_are_jumpers no)
		(fp_line
			(start 0.7874 -0.4064)
			(end 0.7874 0.4064)
			(stroke
				(width 0.1524)
				(type default)
			)
			(layer "F.SilkS")
		)
		(fp_line
			(start -0.7874 -0.4064)
			(end 0.7874 -0.4064)
			(stroke
				(width 0.1524)
				(type default)
			)
			(layer "F.SilkS")
		)
		(fp_line
			(start 0.7874 0.4064)
			(end -0.7874 0.4064)
			(stroke
				(width 0.1524)
				(type default)
			)
			(layer "F.SilkS")
		)
		(fp_line
			(start -0.7874 0.4064)
			(end -0.7874 -0.4064)
			(stroke
				(width 0.1524)
				(type default)
			)
			(layer "F.SilkS")
		)
		(fp_line
			(start -0.12065 -0.305054)
			(end -0.12065 -0.2794)
			(stroke
				(width 0.1)
				(type default)
			)
			(layer "F.Fab")
		)
		(fp_line
			(start -0.67945 -0.305054)
			(end -0.12065 -0.305054)
			(stroke
				(width 0.1)
				(type default)
			)
			(layer "F.Fab")
		)
		(fp_line
			(start 0.67945 -0.3048)
			(end 0.67945 0.3048)
			(stroke
				(width 0.1)
				(type default)
			)
			(layer "F.Fab")
		)
		(fp_line
			(start 0.12065 -0.3048)
			(end 0.67945 -0.3048)
			(stroke
				(width 0.1)
				(type default)
			)
			(layer "F.Fab")
		)
		(fp_line
			(start 0.12065 -0.2794)
			(end 0.12065 -0.3048)
			(stroke
				(width 0.1)
				(type default)
			)
			(layer "F.Fab")
		)
		(fp_line
			(start -0.12065 -0.2794)
			(end 0.12065 -0.2794)
			(stroke
				(width 0.1)
				(type default)
			)
			(layer "F.Fab")
		)
		(fp_line
			(start 0.120396 0.2794)
			(end -0.12065 0.2794)
			(stroke
				(width 0.1)
				(type default)
			)
			(layer "F.Fab")
		)
		(fp_line
			(start -0.12065 0.2794)
			(end -0.12065 0.3048)
			(stroke
				(width 0.1)
				(type default)
			)
			(layer "F.Fab")
		)
		(fp_line
			(start 0.67945 0.3048)
			(end 0.120396 0.3048)
			(stroke
				(width 0.1)
				(type default)
			)
			(layer "F.Fab")
		)
		(fp_line
			(start 0.120396 0.3048)
			(end 0.120396 0.2794)
			(stroke
				(width 0.1)
				(type default)
			)
			(layer "F.Fab")
		)
		(fp_line
			(start -0.12065 0.3048)
			(end -0.67945 0.3048)
			(stroke
				(width 0.1)
				(type default)
			)
			(layer "F.Fab")
		)
		(fp_line
			(start -0.67945 0.3048)
			(end -0.67945 -0.305054)
			(stroke
				(width 0.1)
				(type default)
			)
			(layer "F.Fab")
		)
		(pad "1" smd circle
			(at -0.40005 0 90)
			(size 0 0)
			(layers "F.Cu" "F.Mask" "F.Paste")
			(net "PWRGD_P3V3_R1")
		)
		(pad "2" smd circle
			(at 0.40005 0 90)
			(size 0 0)
			(layers "F.Cu" "F.Mask" "F.Paste")
			(net "PWRGD_P3V3")
		)
	)
	(footprint ""
		(layer "F.Cu")
		(at 198.8312 -128.793748 -90)
		(property "Reference" "R4612"
			(at 0 0 270)
			(layer "F.SilkS")
			(hide yes)
			(effects
				(font
					(size 1.27 1.27)
				)
			)
		)
		(property "Value" ""
			(at 0 0 270)
			(layer "F.Fab")
			(effects
				(font
					(size 1.27 1.27)
				)
			)
		)
		(duplicate_pad_numbers_are_jumpers no)
		(fp_line
			(start -0.7874 0.4064)
			(end -0.7874 -0.4064)
			(stroke
				(width 0.1524)
				(type default)
			)
			(layer "F.SilkS")
		)
		(fp_line
			(start 0.7874 0.4064)
			(end -0.7874 0.4064)
			(stroke
				(width 0.1524)
				(type default)
			)
			(layer "F.SilkS")
		)
		(fp_line
			(start -0.7874 -0.4064)
			(end 0.7874 -0.4064)
			(stroke
				(width 0.1524)
				(type default)
			)
			(layer "F.SilkS")
		)
		(fp_line
			(start 0.7874 -0.4064)
			(end 0.7874 0.4064)
			(stroke
				(width 0.1524)
				(type default)
			)
			(layer "F.SilkS")
		)
		(fp_line
			(start -0.67945 0.3048)
			(end -0.67945 -0.305054)
			(stroke
				(width 0.1)
				(type default)
			)
			(layer "F.Fab")
		)
		(fp_line
			(start -0.12065 0.3048)
			(end -0.67945 0.3048)
			(stroke
				(width 0.1)
				(type default)
			)
			(layer "F.Fab")
		)
		(fp_line
			(start 0.120396 0.3048)
			(end 0.120396 0.2794)
			(stroke
				(width 0.1)
				(type default)
			)
			(layer "F.Fab")
		)
		(fp_line
			(start 0.67945 0.3048)
			(end 0.120396 0.3048)
			(stroke
				(width 0.1)
				(type default)
			)
			(layer "F.Fab")
		)
		(fp_line
			(start -0.12065 0.2794)
			(end -0.12065 0.3048)
			(stroke
				(width 0.1)
				(type default)
			)
			(layer "F.Fab")
		)
		(fp_line
			(start 0.120396 0.2794)
			(end -0.12065 0.2794)
			(stroke
				(width 0.1)
				(type default)
			)
			(layer "F.Fab")
		)
		(fp_line
			(start -0.12065 -0.2794)
			(end 0.12065 -0.2794)
			(stroke
				(width 0.1)
				(type default)
			)
			(layer "F.Fab")
		)
		(fp_line
			(start 0.12065 -0.2794)
			(end 0.12065 -0.3048)
			(stroke
				(width 0.1)
				(type default)
			)
			(layer "F.Fab")
		)
		(fp_line
			(start 0.12065 -0.3048)
			(end 0.67945 -0.3048)
			(stroke
				(width 0.1)
				(type default)
			)
			(layer "F.Fab")
		)
		(fp_line
			(start 0.67945 -0.3048)
			(end 0.67945 0.3048)
			(stroke
				(width 0.1)
				(type default)
			)
			(layer "F.Fab")
		)
		(fp_line
			(start -0.67945 -0.305054)
			(end -0.12065 -0.305054)
			(stroke
				(width 0.1)
				(type default)
			)
			(layer "F.Fab")
		)
		(fp_line
			(start -0.12065 -0.305054)
			(end -0.12065 -0.2794)
			(stroke
				(width 0.1)
				(type default)
			)
			(layer "F.Fab")
		)
		(pad "1" smd circle
			(at -0.40005 0 270)
			(size 0 0)
			(layers "F.Cu" "F.Mask" "F.Paste")
			(net "FM_PCH_SPKR")
		)
		(pad "2" smd circle
			(at 0.40005 0 270)
			(size 0 0)
			(layers "F.Cu" "F.Mask" "F.Paste")
			(net "FM_PCH_SPKR_R")
		)
	)
	(footprint ""
		(layer "F.Cu")
		(at 192.688972 -22.694392)
		(property "Reference" "PR4012"
			(at 0 0 0)
			(layer "F.SilkS")
			(hide yes)
			(effects
				(font
					(size 1.27 1.27)
				)
			)
		)
		(property "Value" ""
			(at 0 0 0)
			(layer "F.Fab")
			(effects
				(font
					(size 1.27 1.27)
				)
			)
		)
		(duplicate_pad_numbers_are_jumpers no)
		(fp_line
			(start -0.7874 -0.4064)
			(end 0.7874 -0.4064)
			(stroke
				(width 0.1524)
				(type default)
			)
			(layer "F.SilkS")
		)
		(fp_line
			(start -0.7874 0.4064)
			(end -0.7874 -0.4064)
			(stroke
				(width 0.1524)
				(type default)
			)
			(layer "F.SilkS")
		)
		(fp_line
			(start 0.7874 -0.4064)
			(end 0.7874 0.4064)
			(stroke
				(width 0.1524)
				(type default)
			)
			(layer "F.SilkS")
		)
		(fp_line
			(start 0.7874 0.4064)
			(end -0.7874 0.4064)
			(stroke
				(width 0.1524)
				(type default)
			)
			(layer "F.SilkS")
		)
		(fp_line
			(start -0.67945 -0.305054)
			(end -0.12065 -0.305054)
			(stroke
				(width 0.1)
				(type default)
			)
			(layer "F.Fab")
		)
		(fp_line
			(start -0.67945 0.3048)
			(end -0.67945 -0.305054)
			(stroke
				(width 0.1)
				(type default)
			)
			(layer "F.Fab")
		)
		(fp_line
			(start -0.12065 -0.305054)
			(end -0.12065 -0.2794)
			(stroke
				(width 0.1)
				(type default)
			)
			(layer "F.Fab")
		)
		(fp_line
			(start -0.12065 -0.2794)
			(end 0.12065 -0.2794)
			(stroke
				(width 0.1)
				(type default)
			)
			(layer "F.Fab")
		)
		(fp_line
			(start -0.12065 0.2794)
			(end -0.12065 0.3048)
			(stroke
				(width 0.1)
				(type default)
			)
			(layer "F.Fab")
		)
		(fp_line
			(start -0.12065 0.3048)
			(end -0.67945 0.3048)
			(stroke
				(width 0.1)
				(type default)
			)
			(layer "F.Fab")
		)
		(fp_line
			(start 0.120396 0.2794)
			(end -0.12065 0.2794)
			(stroke
				(width 0.1)
				(type default)
			)
			(layer "F.Fab")
		)
		(fp_line
			(start 0.120396 0.3048)
			(end 0.120396 0.2794)
			(stroke
				(width 0.1)
				(type default)
			)
			(layer "F.Fab")
		)
		(fp_line
			(start 0.12065 -0.3048)
			(end 0.67945 -0.3048)
			(stroke
				(width 0.1)
				(type default)
			)
			(layer "F.Fab")
		)
		(fp_line
			(start 0.12065 -0.2794)
			(end 0.12065 -0.3048)
			(stroke
				(width 0.1)
				(type default)
			)
			(layer "F.Fab")
		)
		(fp_line
			(start 0.67945 -0.3048)
			(end 0.67945 0.3048)
			(stroke
				(width 0.1)
				(type default)
			)
			(layer "F.Fab")
		)
		(fp_line
			(start 0.67945 0.3048)
			(end 0.120396 0.3048)
			(stroke
				(width 0.1)
				(type default)
			)
			(layer "F.Fab")
		)
		(pad "1" smd circle
			(at -0.40005 0)
			(size 0 0)
			(layers "F.Cu" "F.Mask" "F.Paste")
			(net "P12V_SCM_PWRGD")
		)
		(pad "2" smd circle
			(at 0.40005 0)
			(size 0 0)
			(layers "F.Cu" "F.Mask" "F.Paste")
			(net "HP_LVC3_SCM_HSC_PWRGD")
		)
	)
	(footprint ""
		(layer "F.Cu")
		(at 289.116008 -412.34614)
		(property "Reference" "Q145"
			(at -1.438148 1.759204 0)
			(unlocked yes)
			(layer "F.SilkS")
			(effects
				(font
					(size 0.7874 0.5842)
					(thickness 0.1524)
				)
				(justify left)
			)
		)
		(property "Value" ""
			(at 0 0 0)
			(layer "F.Fab")
			(effects
				(font
					(size 1.27 1.27)
				)
			)
		)
		(duplicate_pad_numbers_are_jumpers no)
		(fp_line
			(start -1.332738 -1.100074)
			(end -0.4826 -1.100074)
			(stroke
				(width 0.1524)
				(type default)
			)
			(layer "F.SilkS")
		)
		(fp_line
			(start -1.332738 1.100074)
			(end -1.332738 -1.100074)
			(stroke
				(width 0.1524)
				(type default)
			)
			(layer "F.SilkS")
		)
		(fp_line
			(start -0.4826 -1.100074)
			(end 0 -0.541274)
			(stroke
				(width 0.1524)
				(type default)
			)
			(layer "F.SilkS")
		)
		(fp_line
			(start 0 -0.541274)
			(end 0.4826 -1.100074)
			(stroke
				(width 0.1524)
				(type default)
			)
			(layer "F.SilkS")
		)
		(fp_line
			(start 0.4826 -1.100074)
			(end 1.332738 -1.100074)
			(stroke
				(width 0.1524)
				(type default)
			)
			(layer "F.SilkS")
		)
		(fp_line
			(start 1.332738 -1.100074)
			(end 1.332738 1.100074)
			(stroke
				(width 0.1524)
				(type default)
			)
			(layer "F.SilkS")
		)
		(fp_line
			(start 1.332738 1.100074)
			(end -1.332738 1.100074)
			(stroke
				(width 0.1524)
				(type default)
			)
			(layer "F.SilkS")
		)
		(fp_poly
			(pts
				(xy -1.756156 -1.726946) (xy -1.507998 -0.982218) (xy -2.252726 -1.230376)
			)
			(stroke
				(width 0)
				(type default)
			)
			(fill yes)
			(layer "F.SilkS")
		)
		(fp_line
			(start -0.674878 -1.100074)
			(end 0.674878 -1.100074)
			(stroke
				(width 0.1)
				(type default)
			)
			(layer "F.Fab")
		)
		(fp_line
			(start -0.674878 1.100074)
			(end -0.674878 -1.100074)
			(stroke
				(width 0.1)
				(type default)
			)
			(layer "F.Fab")
		)
		(fp_line
			(start 0.674878 -1.100074)
			(end 0.674878 1.100074)
			(stroke
				(width 0.1)
				(type default)
			)
			(layer "F.Fab")
		)
		(fp_line
			(start 0.674878 1.100074)
			(end -0.674878 1.100074)
			(stroke
				(width 0.1)
				(type default)
			)
			(layer "F.Fab")
		)
		(fp_poly
			(pts
				(xy -2.2352 -0.298958) (xy -2.2352 -1.001014) (xy -1.533144 -0.649986)
			)
			(stroke
				(width 0)
				(type default)
			)
			(fill yes)
			(layer "F.Fab")
		)
		(pad "1" smd rect
			(at -0.94996 -0.649986 90)
			(size 0.4318 0.508)
			(layers "F.Cu" "F.Mask" "F.Paste")
			(net "GND")
		)
		(pad "2" smd rect
			(at -0.94996 0 90)
			(size 0.4318 0.508)
			(layers "F.Cu" "F.Mask" "F.Paste")
			(net "HPDB_HSC_PWRGD")
		)
		(pad "3" smd rect
			(at -0.94996 0.649986 90)
			(size 0.4318 0.508)
			(layers "F.Cu" "F.Mask" "F.Paste")
			(net "HPDB_HSC_PWRGD_ISO")
		)
		(pad "4" smd rect
			(at 0.94996 0.649986 90)
			(size 0.4318 0.508)
			(layers "F.Cu" "F.Mask" "F.Paste")
			(net "GND")
		)
		(pad "5" smd rect
			(at 0.94996 0 90)
			(size 0.4318 0.508)
			(layers "F.Cu" "F.Mask" "F.Paste")
			(net "HPDB_HSC_PWRGD_N")
		)
		(pad "6" smd rect
			(at 0.94996 -0.649986 90)
			(size 0.4318 0.508)
			(layers "F.Cu" "F.Mask" "F.Paste")
			(net "HPDB_HSC_PWRGD_N")
		)
	)
	(footprint ""
		(layer "F.Cu")
		(at 420.66972 -132.21716 180)
		(property "Reference" "PC2362"
			(at 0 0 180)
			(layer "F.SilkS")
			(hide yes)
			(effects
				(font
					(size 1.27 1.27)
				)
			)
		)
		(property "Value" ""
			(at 0 0 180)
			(layer "F.Fab")
			(effects
				(font
					(size 1.27 1.27)
				)
			)
		)
		(duplicate_pad_numbers_are_jumpers no)
		(fp_line
			(start 0.7874 0.4064)
			(end -0.7874 0.4064)
			(stroke
				(width 0.1524)
				(type default)
			)
			(layer "F.SilkS")
		)
		(fp_line
			(start 0.7874 -0.4064)
			(end 0.7874 0.4064)
			(stroke
				(width 0.1524)
				(type default)
			)
			(layer "F.SilkS")
		)
		(fp_line
			(start -0.7874 0.4064)
			(end -0.7874 -0.4064)
			(stroke
				(width 0.1524)
				(type default)
			)
			(layer "F.SilkS")
		)
		(fp_line
			(start -0.7874 -0.4064)
			(end 0.7874 -0.4064)
			(stroke
				(width 0.1524)
				(type default)
			)
			(layer "F.SilkS")
		)
		(fp_line
			(start 0.67945 0.3048)
			(end 0.120396 0.3048)
			(stroke
				(width 0.1)
				(type default)
			)
			(layer "F.Fab")
		)
		(fp_line
			(start 0.67945 -0.3048)
			(end 0.67945 0.3048)
			(stroke
				(width 0.1)
				(type default)
			)
			(layer "F.Fab")
		)
		(fp_line
			(start 0.12065 -0.2794)
			(end 0.12065 -0.3048)
			(stroke
				(width 0.1)
				(type default)
			)
			(layer "F.Fab")
		)
		(fp_line
			(start 0.12065 -0.3048)
			(end 0.67945 -0.3048)
			(stroke
				(width 0.1)
				(type default)
			)
			(layer "F.Fab")
		)
		(fp_line
			(start 0.120396 0.3048)
			(end 0.120396 0.2794)
			(stroke
				(width 0.1)
				(type default)
			)
			(layer "F.Fab")
		)
		(fp_line
			(start 0.120396 0.2794)
			(end -0.12065 0.2794)
			(stroke
				(width 0.1)
				(type default)
			)
			(layer "F.Fab")
		)
		(fp_line
			(start -0.12065 0.3048)
			(end -0.67945 0.3048)
			(stroke
				(width 0.1)
				(type default)
			)
			(layer "F.Fab")
		)
		(fp_line
			(start -0.12065 0.2794)
			(end -0.12065 0.3048)
			(stroke
				(width 0.1)
				(type default)
			)
			(layer "F.Fab")
		)
		(fp_line
			(start -0.12065 -0.2794)
			(end 0.12065 -0.2794)
			(stroke
				(width 0.1)
				(type default)
			)
			(layer "F.Fab")
		)
		(fp_line
			(start -0.12065 -0.305054)
			(end -0.12065 -0.2794)
			(stroke
				(width 0.1)
				(type default)
			)
			(layer "F.Fab")
		)
		(fp_line
			(start -0.67945 0.3048)
			(end -0.67945 -0.305054)
			(stroke
				(width 0.1)
				(type default)
			)
			(layer "F.Fab")
		)
		(fp_line
			(start -0.67945 -0.305054)
			(end -0.12065 -0.305054)
			(stroke
				(width 0.1)
				(type default)
			)
			(layer "F.Fab")
		)
		(pad "1" smd circle
			(at -0.40005 0 180)
			(size 0 0)
			(layers "F.Cu" "F.Mask" "F.Paste")
			(net "PVCCINFAON_CPU0_VCC")
		)
		(pad "2" smd circle
			(at 0.40005 0 180)
			(size 0 0)
			(layers "F.Cu" "F.Mask" "F.Paste")
			(net "GND")
		)
	)
)
